(kicad_pcb
	(version 20260206)
	(generator "pcbnew")
	(generator_version "10.0")
	(general
		(thickness 1.6)
		(legacy_teardrops no)
	)
	(paper "A4")
	(title_block
		(title "Bryce Canyon_F.DPB_16315-1-OCP.brd")
		(comment 1 "Bryce Canyon / footprints 505-511 of 2223")
	)
	(layers
		(0 "F.Cu" signal "TOP")
		(4 "In1.Cu" signal "L2GND")
		(6 "In2.Cu" signal "L3")
		(8 "In3.Cu" signal "L4GND")
		(10 "In4.Cu" signal "L5")
		(12 "In5.Cu" signal "L6VCC")
		(14 "In6.Cu" signal "L7VCC")
		(16 "In7.Cu" signal "L8")
		(18 "In8.Cu" signal "L9GND")
		(20 "In9.Cu" signal "L10")
		(22 "In10.Cu" signal "L11GND")
		(2 "B.Cu" signal "BOTTOM")
		(9 "F.Adhes" user "F.Adhesive")
		(11 "B.Adhes" user "B.Adhesive")
		(13 "F.Paste" user "Package Geometry/Pastemask Top")
		(15 "B.Paste" user "Package Geometry/Pastemask Bottom")
		(5 "F.SilkS" user "Ref Des/Silkscreen Top")
		(7 "B.SilkS" user "Ref Des/Silkscreen Bottom")
		(1 "F.Mask" user "Board Geometry/Soldermask Top")
		(3 "B.Mask" user "Board Geometry/Soldermask Bottom")
		(17 "Dwgs.User" user "User.Drawings")
		(19 "Cmts.User" user "User.Comments")
		(21 "Eco1.User" user "User.Eco1")
		(23 "Eco2.User" user "User.Eco2")
		(25 "Edge.Cuts" user "Board Geometry/Outline")
		(27 "Margin" user)
		(31 "F.CrtYd" user "Package Geometry/Place Bound Top")
		(29 "B.CrtYd" user "Package Geometry/Place Bound Bottom")
		(35 "F.Fab" user "Ref Des/Assembly Top")
		(33 "B.Fab" user "Ref Des/Assembly Bottom")
	)
	(footprint ""
		(layer "F.Cu")
		(at 272.542 -336.104992 180)
		(property "Reference" "VIA47"
			(at 0 0 180)
			(layer "F.SilkS")
			(hide yes)
			(effects
				(font
					(size 1.27 1.27)
				)
			)
		)
		(property "Value" "100OHM-8L-1D6MM-L18L16-GP"
			(at -3.7211 -4.5085 180)
			(unlocked yes)
			(layer "F.Fab")
			(hide yes)
			(effects
				(font
					(size 1.016 1.016)
					(thickness 0.1524)
				)
			)
		)
		(property "Device Type" "VIA-PCIE-4P-394076"
			(at -3.7211 -6.0325 180)
			(unlocked yes)
			(layer "F.Fab")
			(hide yes)
			(effects
				(font
					(size 1.016 1.016)
					(thickness 0.1524)
				)
			)
		)
		(duplicate_pad_numbers_are_jumpers no)
		(fp_rect
			(start -1.9685 0.381)
			(end 1.9685 -0.381)
			(stroke
				(width 0)
				(type default)
			)
			(fill no)
			(layer "F.CrtYd")
		)
		(fp_rect
			(start -1.9685 0.381)
			(end 1.9685 -0.381)
			(stroke
				(width 0)
				(type default)
			)
			(fill no)
			(layer "F.Fab")
		)
		(pad "1" thru_hole circle
			(at -1.5875 0 180)
			(size 0.508 0.508)
			(drill 0.254)
			(layers "*.Cu" "*.Mask")
			(remove_unused_layers no)
			(net "GND")
			(clearance 0.127)
			(thermal_gap 0.127)
		)
		(pad "2" thru_hole circle
			(at -0.5715 0 180)
			(size 0.508 0.508)
			(drill 0.254)
			(layers "*.Cu" "*.Mask")
			(remove_unused_layers no)
			(net "PHY_SCC_A_TO_DRV_A_13_DP")
			(clearance 0.127)
			(thermal_gap 0.127)
		)
		(pad "3" thru_hole circle
			(at 0.5715 0 180)
			(size 0.508 0.508)
			(drill 0.254)
			(layers "*.Cu" "*.Mask")
			(remove_unused_layers no)
			(net "PHY_SCC_A_TO_DRV_A_13_DN")
			(clearance 0.127)
			(thermal_gap 0.127)
		)
		(pad "4" thru_hole circle
			(at 1.5875 0 180)
			(size 0.508 0.508)
			(drill 0.254)
			(layers "*.Cu" "*.Mask")
			(remove_unused_layers no)
			(net "GND")
			(clearance 0.127)
			(thermal_gap 0.127)
		)
	)
	(footprint ""
		(layer "F.Cu")
		(at 67.347846 -62.169294 -90)
		(property "Reference" "R705"
			(at 0 0 270)
			(layer "F.SilkS")
			(hide yes)
			(effects
				(font
					(size 1.27 1.27)
				)
			)
		)
		(property "Value" "10KR2F-2-GP"
			(at 0.064008 -3.993896 270)
			(unlocked yes)
			(layer "F.Fab")
			(hide yes)
			(effects
				(font
					(size 1.016 1.016)
					(thickness 0.1524)
				)
			)
		)
		(property "Device Type" "R402H16"
			(at 0.064008 -5.517896 270)
			(unlocked yes)
			(layer "F.Fab")
			(hide yes)
			(effects
				(font
					(size 1.016 1.016)
					(thickness 0.1524)
				)
			)
		)
		(duplicate_pad_numbers_are_jumpers no)
		(fp_line
			(start -0.508 -0.9398)
			(end -0.508 0.9398)
			(stroke
				(width 0.1524)
				(type default)
			)
			(layer "F.SilkS")
		)
		(fp_line
			(start 0.508 -0.9398)
			(end -0.508 -0.9398)
			(stroke
				(width 0.1524)
				(type default)
			)
			(layer "F.SilkS")
		)
		(fp_rect
			(start -0.508 0.9398)
			(end 0.508 -0.9398)
			(stroke
				(width 0)
				(type default)
			)
			(fill no)
			(layer "F.CrtYd")
		)
		(fp_rect
			(start -0.508 0.9398)
			(end 0.508 -0.9398)
			(stroke
				(width 0)
				(type default)
			)
			(fill no)
			(layer "F.Fab")
		)
		(pad "1" smd custom
			(at 0 -0.4445 270)
			(size 0.1397 0.1397)
			(layers "F.Cu" "F.Mask" "F.Paste")
			(net "P3V3_STBY_A")
			(options
				(clearance outline)
				(anchor circle)
			)
			(primitives
				(gr_poly
					(pts
						(arc
							(start -0.1778 -0.2794)
							(mid -0.249642 -0.249642)
							(end -0.2794 -0.1778)
						)
						(arc
							(start -0.2794 0.1778)
							(mid -0.249642 0.249642)
							(end -0.1778 0.2794)
						)
						(arc
							(start 0.1778 0.2794)
							(mid 0.249642 0.249642)
							(end 0.2794 0.1778)
						)
						(arc
							(start 0.2794 -0.1778)
							(mid 0.249642 -0.249642)
							(end 0.1778 -0.2794)
						)
					)
					(width 0)
					(fill yes)
				)
			)
		)
		(pad "2" smd custom
			(at 0 0.4445 270)
			(size 0.1397 0.1397)
			(layers "F.Cu" "F.Mask" "F.Paste")
			(net "HDD_PRSNT_25")
			(options
				(clearance outline)
				(anchor circle)
			)
			(primitives
				(gr_poly
					(pts
						(arc
							(start -0.1778 -0.2794)
							(mid -0.249642 -0.249642)
							(end -0.2794 -0.1778)
						)
						(arc
							(start -0.2794 0.1778)
							(mid -0.249642 0.249642)
							(end -0.1778 0.2794)
						)
						(arc
							(start 0.1778 0.2794)
							(mid 0.249642 0.249642)
							(end 0.2794 0.1778)
						)
						(arc
							(start 0.2794 -0.1778)
							(mid 0.249642 -0.249642)
							(end 0.1778 -0.2794)
						)
					)
					(width 0)
					(fill yes)
				)
			)
		)
	)
	(footprint ""
		(layer "F.Cu")
		(at 222.693992 -344.628978)
		(property "Reference" "R23"
			(at 0 0 0)
			(layer "F.SilkS")
			(hide yes)
			(effects
				(font
					(size 1.27 1.27)
				)
			)
		)
		(property "Value" "4K7R2F-GP"
			(at 0.064008 -3.993896 0)
			(unlocked yes)
			(layer "F.Fab")
			(hide yes)
			(effects
				(font
					(size 1.016 1.016)
					(thickness 0.1524)
				)
			)
		)
		(property "Device Type" "R402H16"
			(at 0.064008 -5.517896 0)
			(unlocked yes)
			(layer "F.Fab")
			(hide yes)
			(effects
				(font
					(size 1.016 1.016)
					(thickness 0.1524)
				)
			)
		)
		(duplicate_pad_numbers_are_jumpers no)
		(fp_line
			(start -0.508 -0.9398)
			(end -0.508 0.9398)
			(stroke
				(width 0.1524)
				(type default)
			)
			(layer "F.SilkS")
		)
		(fp_line
			(start 0.508 -0.9398)
			(end -0.508 -0.9398)
			(stroke
				(width 0.1524)
				(type default)
			)
			(layer "F.SilkS")
		)
		(fp_rect
			(start -0.508 0.9398)
			(end 0.508 -0.9398)
			(stroke
				(width 0)
				(type default)
			)
			(fill no)
			(layer "F.CrtYd")
		)
		(fp_rect
			(start -0.508 0.9398)
			(end 0.508 -0.9398)
			(stroke
				(width 0)
				(type default)
			)
			(fill no)
			(layer "F.Fab")
		)
		(pad "1" smd custom
			(at 0 -0.4445)
			(size 0.1397 0.1397)
			(layers "F.Cu" "F.Mask" "F.Paste")
			(net "P3V3_STBY_A")
			(options
				(clearance outline)
				(anchor circle)
			)
			(primitives
				(gr_poly
					(pts
						(arc
							(start -0.1778 -0.2794)
							(mid -0.249642 -0.249642)
							(end -0.2794 -0.1778)
						)
						(arc
							(start -0.2794 0.1778)
							(mid -0.249642 0.249642)
							(end -0.1778 0.2794)
						)
						(arc
							(start 0.1778 0.2794)
							(mid 0.249642 0.249642)
							(end 0.2794 0.1778)
						)
						(arc
							(start 0.2794 -0.1778)
							(mid 0.249642 -0.249642)
							(end 0.1778 -0.2794)
						)
					)
					(width 0)
					(fill yes)
				)
			)
		)
		(pad "2" smd custom
			(at 0 0.4445)
			(size 0.1397 0.1397)
			(layers "F.Cu" "F.Mask" "F.Paste")
			(net "VOL_SEN_ADDR0")
			(options
				(clearance outline)
				(anchor circle)
			)
			(primitives
				(gr_poly
					(pts
						(arc
							(start -0.1778 -0.2794)
							(mid -0.249642 -0.249642)
							(end -0.2794 -0.1778)
						)
						(arc
							(start -0.2794 0.1778)
							(mid -0.249642 0.249642)
							(end -0.1778 0.2794)
						)
						(arc
							(start 0.1778 0.2794)
							(mid 0.249642 0.249642)
							(end 0.2794 0.1778)
						)
						(arc
							(start 0.2794 -0.1778)
							(mid 0.249642 -0.249642)
							(end 0.1778 -0.2794)
						)
					)
					(width 0)
					(fill yes)
				)
			)
		)
	)
	(footprint ""
		(layer "F.Cu")
		(at 378.7394 -134.8486 90)
		(property "Reference" "R1080"
			(at 0 0 90)
			(layer "F.SilkS")
			(hide yes)
			(effects
				(font
					(size 1.27 1.27)
				)
			)
		)
		(property "Value" "0R0603-PAD-2-GP-U"
			(at 2.1209 -0.1397 90)
			(unlocked yes)
			(layer "F.Fab")
			(hide yes)
			(effects
				(font
					(size 1.016 1.016)
					(thickness 0.1524)
				)
			)
		)
		(property "Device Type" "0R0603-PAD-1-U"
			(at 2.1209 -1.6637 90)
			(unlocked yes)
			(layer "F.Fab")
			(hide yes)
			(effects
				(font
					(size 1.016 1.016)
					(thickness 0.1524)
				)
			)
		)
		(duplicate_pad_numbers_are_jumpers no)
		(fp_rect
			(start -0.5842 1.3335)
			(end 0.5842 -1.3335)
			(stroke
				(width 0)
				(type default)
			)
			(fill no)
			(layer "F.CrtYd")
		)
		(fp_rect
			(start -0.5842 1.3335)
			(end 0.5842 -1.3335)
			(stroke
				(width 0)
				(type default)
			)
			(fill no)
			(layer "F.Fab")
		)
		(pad "1" smd custom
			(at 0 -0.762 90)
			(size 0.2159 0.2159)
			(layers "F.Cu" "F.Mask" "F.Paste")
			(net "AGND_CURRENT_MONOB")
			(options
				(clearance outline)
				(anchor circle)
			)
			(primitives
				(gr_poly
					(pts
						(arc
							(start -0.3302 -0.5842)
							(mid -0.402042 -0.554442)
							(end -0.4318 -0.4826)
						)
						(arc
							(start -0.4318 0.4826)
							(mid -0.402042 0.554442)
							(end -0.3302 0.5842)
						)
						(arc
							(start 0.3302 0.5842)
							(mid 0.402042 0.554442)
							(end 0.4318 0.4826)
						)
						(arc
							(start 0.4318 -0.4826)
							(mid 0.402042 -0.554442)
							(end 0.3302 -0.5842)
						)
					)
					(width 0)
					(fill yes)
				)
			)
		)
		(pad "2" smd custom
			(at 0 0.762 90)
			(size 0.2159 0.2159)
			(layers "F.Cu" "F.Mask" "F.Paste")
			(net "GND")
			(options
				(clearance outline)
				(anchor circle)
			)
			(primitives
				(gr_poly
					(pts
						(arc
							(start -0.4318 0.4826)
							(mid -0.402042 0.554442)
							(end -0.3302 0.5842)
						)
						(arc
							(start 0.3302 0.5842)
							(mid 0.402042 0.554442)
							(end 0.4318 0.4826)
						)
						(arc
							(start 0.4318 -0.4826)
							(mid 0.402042 -0.554442)
							(end 0.3302 -0.5842)
						)
						(arc
							(start -0.3302 -0.5842)
							(mid -0.402042 -0.554442)
							(end -0.4318 -0.4826)
						)
					)
					(width 0)
					(fill yes)
				)
			)
		)
	)
	(footprint ""
		(layer "F.Cu")
		(at 52.234846 -55.285894 180)
		(property "Reference" "Q149"
			(at 0 0 180)
			(layer "F.SilkS")
			(hide yes)
			(effects
				(font
					(size 1.27 1.27)
				)
			)
		)
		(property "Value" "AO4406AL-GP"
			(at -3.707384 -1.5367 180)
			(unlocked yes)
			(layer "F.Fab")
			(hide yes)
			(effects
				(font
					(size 1.016 1.016)
					(thickness 0.1524)
				)
			)
		)
		(property "Device Type" "SOIC8H69"
			(at -3.707384 -3.0607 180)
			(unlocked yes)
			(layer "F.Fab")
			(hide yes)
			(effects
				(font
					(size 1.016 1.016)
					(thickness 0.1524)
				)
			)
		)
		(duplicate_pad_numbers_are_jumpers no)
		(fp_line
			(start 2.1336 1.4224)
			(end 2.1336 -1.4224)
			(stroke
				(width 0.1524)
				(type default)
			)
			(layer "F.SilkS")
		)
		(fp_line
			(start 2.1336 -1.4224)
			(end -2.7432 -1.4224)
			(stroke
				(width 0.1524)
				(type default)
			)
			(layer "F.SilkS")
		)
		(fp_line
			(start -2.1844 -0.0508)
			(end -2.7178 0.508)
			(stroke
				(width 0.1524)
				(type default)
			)
			(layer "F.SilkS")
		)
		(fp_line
			(start -2.6289 3.4417)
			(end -2.6289 1.4732)
			(stroke
				(width 0.381)
				(type default)
			)
			(layer "F.SilkS")
		)
		(fp_line
			(start -2.7178 -0.508)
			(end -2.1844 -0.0508)
			(stroke
				(width 0.1524)
				(type default)
			)
			(layer "F.SilkS")
		)
		(fp_line
			(start -2.7432 1.4224)
			(end 2.1336 1.4224)
			(stroke
				(width 0.1524)
				(type default)
			)
			(layer "F.SilkS")
		)
		(fp_line
			(start -2.7432 1.4224)
			(end -2.6416 1.4224)
			(stroke
				(width 0.1524)
				(type default)
			)
			(layer "F.SilkS")
		)
		(fp_line
			(start -2.7432 -1.4224)
			(end -2.7432 1.4224)
			(stroke
				(width 0.1524)
				(type default)
			)
			(layer "F.SilkS")
		)
		(fp_poly
			(pts
				(xy -2.2098 -1.4224) (xy -2.2098 1.4224) (xy 2.2098 1.4224) (xy 2.2098 -1.4224)
			)
			(stroke
				(width 0)
				(type default)
			)
			(fill yes)
			(layer "F.SilkS")
		)
		(fp_rect
			(start -2.450084 2.999994)
			(end 2.450084 -2.999994)
			(stroke
				(width 0)
				(type default)
			)
			(fill no)
			(layer "F.CrtYd")
		)
		(fp_poly
			(pts
				(xy -2.8194 3.6322) (xy -2.8194 -3.6322) (xy 2.8194 -3.6322) (xy 2.8194 1.18364) (xy 2.450084 1.18364)
				(xy 2.450084 -2.999994) (xy -2.450084 -2.999994) (xy -2.450084 2.999994) (xy 2.450084 2.999994)
				(xy 2.450084 1.18618) (xy 2.8194 1.18618) (xy 2.8194 3.6322)
			)
			(stroke
				(width 0)
				(type default)
			)
			(fill no)
			(layer "F.CrtYd")
		)
		(fp_rect
			(start -2.8194 3.6322)
			(end 2.8194 -3.6322)
			(stroke
				(width 0)
				(type default)
			)
			(fill no)
			(layer "F.Fab")
		)
		(pad "1" smd rect
			(at -1.905 2.54 180)
			(size 0.635 1.651)
			(layers "F.Cu" "F.Mask" "F.Paste")
			(net "P5V_HDD25")
		)
		(pad "2" smd rect
			(at -0.635 2.54 180)
			(size 0.635 1.651)
			(layers "F.Cu" "F.Mask" "F.Paste")
			(net "P5V_HDD25")
		)
		(pad "3" smd rect
			(at 0.635 2.54 180)
			(size 0.635 1.651)
			(layers "F.Cu" "F.Mask" "F.Paste")
			(net "P5V_HDD25")
		)
		(pad "4" smd rect
			(at 1.905 2.54 180)
			(size 0.635 1.651)
			(layers "F.Cu" "F.Mask" "F.Paste")
			(net "SW_HDD_P25")
		)
		(pad "5" smd rect
			(at 1.905 -2.54 180)
			(size 0.635 1.651)
			(layers "F.Cu" "F.Mask" "F.Paste")
			(net "P5V_A_2")
		)
		(pad "6" smd rect
			(at 0.635 -2.54 180)
			(size 0.635 1.651)
			(layers "F.Cu" "F.Mask" "F.Paste")
			(net "P5V_A_2")
		)
		(pad "7" smd rect
			(at -0.635 -2.54 180)
			(size 0.635 1.651)
			(layers "F.Cu" "F.Mask" "F.Paste")
			(net "P5V_A_2")
		)
		(pad "8" smd rect
			(at -1.905 -2.54 180)
			(size 0.635 1.651)
			(layers "F.Cu" "F.Mask" "F.Paste")
			(net "P5V_A_2")
		)
	)
	(footprint ""
		(layer "F.Cu")
		(at 258.694682 -371.88775)
		(property "Reference" "R1174"
			(at 0 0 0)
			(layer "F.SilkS")
			(hide yes)
			(effects
				(font
					(size 1.27 1.27)
				)
			)
		)
		(property "Value" "10R5F-1-GP"
			(at 0 -8.9535 0)
			(unlocked yes)
			(layer "F.Fab")
			(hide yes)
			(effects
				(font
					(size 1.27 1.016)
					(thickness 0.1524)
				)
			)
		)
		(property "Device Type" "R805H24"
			(at 0 -10.6299 0)
			(unlocked yes)
			(layer "F.Fab")
			(hide yes)
			(effects
				(font
					(size 1.27 1.016)
					(thickness 0.1524)
				)
			)
		)
		(duplicate_pad_numbers_are_jumpers no)
		(fp_line
			(start -0.889 -1.7018)
			(end -0.889 0.2794)
			(stroke
				(width 0.1524)
				(type default)
			)
			(layer "F.SilkS")
		)
		(fp_line
			(start -0.889 0.0762)
			(end -0.889 1.7018)
			(stroke
				(width 0.1524)
				(type default)
			)
			(layer "F.SilkS")
		)
		(fp_line
			(start -0.889 1.7018)
			(end 0.889 1.7018)
			(stroke
				(width 0.1524)
				(type default)
			)
			(layer "F.SilkS")
		)
		(fp_line
			(start 0.889 -1.7018)
			(end -0.889 -1.7018)
			(stroke
				(width 0.1524)
				(type default)
			)
			(layer "F.SilkS")
		)
		(fp_line
			(start 0.889 -1.7018)
			(end 0.889 -0.381)
			(stroke
				(width 0.1524)
				(type default)
			)
			(layer "F.SilkS")
		)
		(fp_line
			(start 0.889 1.7018)
			(end 0.889 -0.508)
			(stroke
				(width 0.1524)
				(type default)
			)
			(layer "F.SilkS")
		)
		(fp_poly
			(pts
				(xy 0.9652 -1.778) (xy 0.9652 1.778) (xy -0.9652 1.778) (xy -0.9652 -1.778)
			)
			(stroke
				(width 0)
				(type default)
			)
			(fill no)
			(layer "F.CrtYd")
		)
		(fp_rect
			(start -0.9652 1.778)
			(end 0.9652 -1.778)
			(stroke
				(width 0)
				(type default)
			)
			(fill no)
			(layer "F.Fab")
		)
		(pad "1" smd rect
			(at 0 -0.9652)
			(size 1.397 1.143)
			(layers "F.Cu" "F.Mask" "F.Paste")
			(net "MB3_12V_CTRL_GATE3")
		)
		(pad "2" smd rect
			(at 0 0.9652)
			(size 1.397 1.143)
			(layers "F.Cu" "F.Mask" "F.Paste")
			(net "MB3_CM_GATE_R")
		)
	)
	(footprint ""
		(layer "F.Cu")
		(at 427.898052 -157.585918 180)
		(property "Reference" "R621"
			(at 0 0 180)
			(layer "F.SilkS")
			(hide yes)
			(effects
				(font
					(size 1.27 1.27)
				)
			)
		)
		(property "Value" "1KR2F-3-GP"
			(at 0.064008 -3.993896 180)
			(unlocked yes)
			(layer "F.Fab")
			(hide yes)
			(effects
				(font
					(size 1.016 1.016)
					(thickness 0.1524)
				)
			)
		)
		(property "Device Type" "R402H16"
			(at 0.064008 -5.517896 180)
			(unlocked yes)
			(layer "F.Fab")
			(hide yes)
			(effects
				(font
					(size 1.016 1.016)
					(thickness 0.1524)
				)
			)
		)
		(duplicate_pad_numbers_are_jumpers no)
		(fp_line
			(start 0.508 -0.9398)
			(end -0.508 -0.9398)
			(stroke
				(width 0.1524)
				(type default)
			)
			(layer "F.SilkS")
		)
		(fp_line
			(start -0.508 -0.9398)
			(end -0.508 0.9398)
			(stroke
				(width 0.1524)
				(type default)
			)
			(layer "F.SilkS")
		)
		(fp_rect
			(start -0.508 0.9398)
			(end 0.508 -0.9398)
			(stroke
				(width 0)
				(type default)
			)
			(fill no)
			(layer "F.CrtYd")
		)
		(fp_rect
			(start -0.508 0.9398)
			(end 0.508 -0.9398)
			(stroke
				(width 0)
				(type default)
			)
			(fill no)
			(layer "F.Fab")
		)
		(pad "1" smd custom
			(at 0 -0.4445 180)
			(size 0.1397 0.1397)
			(layers "F.Cu" "F.Mask" "F.Paste")
			(net "P3V3_STBY_A")
			(options
				(clearance outline)
				(anchor circle)
			)
			(primitives
				(gr_poly
					(pts
						(arc
							(start -0.1778 -0.2794)
							(mid -0.249642 -0.249642)
							(end -0.2794 -0.1778)
						)
						(arc
							(start -0.2794 0.1778)
							(mid -0.249642 0.249642)
							(end -0.1778 0.2794)
						)
						(arc
							(start 0.1778 0.2794)
							(mid 0.249642 0.249642)
							(end 0.2794 0.1778)
						)
						(arc
							(start 0.2794 -0.1778)
							(mid 0.249642 -0.249642)
							(end 0.1778 -0.2794)
						)
					)
					(width 0)
					(fill yes)
				)
			)
		)
		(pad "2" smd custom
			(at 0 0.4445 180)
			(size 0.1397 0.1397)
			(layers "F.Cu" "F.Mask" "F.Paste")
			(net "SW_PWR_R_HDD21")
			(options
				(clearance outline)
				(anchor circle)
			)
			(primitives
				(gr_poly
					(pts
						(arc
							(start -0.1778 -0.2794)
							(mid -0.249642 -0.249642)
							(end -0.2794 -0.1778)
						)
						(arc
							(start -0.2794 0.1778)
							(mid -0.249642 0.249642)
							(end -0.1778 0.2794)
						)
						(arc
							(start 0.1778 0.2794)
							(mid 0.249642 0.249642)
							(end 0.2794 0.1778)
						)
						(arc
							(start 0.2794 -0.1778)
							(mid 0.249642 -0.249642)
							(end 0.1778 -0.2794)
						)
					)
					(width 0)
					(fill yes)
				)
			)
		)
	)
)
